(kicad_pcb
	(version 20260206)
	(generator "pcbnew")
	(generator_version "10.0")
	(general
		(thickness 1.6)
		(legacy_teardrops no)
	)
	(paper "A4")
	(title_block
		(title "04192023_DAF0TMB3IC0_F0TG_MB_C_brd_V02_OCP.brd")
		(comment 1 "Grand Teton / footprint 3169 of 8354 (U6016), pads 112-223 of 354")
	)
	(layers
		(0 "F.Cu" signal "TOP")
		(4 "In1.Cu" signal "GND")
		(6 "In2.Cu" signal "IN1")
		(8 "In3.Cu" signal "GND1")
		(10 "In4.Cu" signal "IN2")
		(12 "In5.Cu" signal "GND2")
		(14 "In6.Cu" signal "IN3")
		(16 "In7.Cu" signal "GND3")
		(18 "In8.Cu" signal "VCC")
		(20 "In9.Cu" signal "VCC1")
		(22 "In10.Cu" signal "GND4")
		(24 "In11.Cu" signal "IN4")
		(26 "In12.Cu" signal "GND5")
		(28 "In13.Cu" signal "IN5")
		(30 "In14.Cu" signal "GND6")
		(32 "In15.Cu" signal "IN6")
		(34 "In16.Cu" signal "GND7")
		(2 "B.Cu" signal "BOTTOM")
		(9 "F.Adhes" user "F.Adhesive")
		(11 "B.Adhes" user "B.Adhesive")
		(13 "F.Paste" user "Package Geometry/Pastemask Top")
		(15 "B.Paste" user "Package Geometry/Pastemask Bottom")
		(5 "F.SilkS" user "Ref Des/Silkscreen Top")
		(7 "B.SilkS" user "Ref Des/Silkscreen Bottom")
		(1 "F.Mask" user "Board Geometry/Soldermask Top")
		(3 "B.Mask" user "Board Geometry/Soldermask Bottom")
		(17 "Dwgs.User" user "User.Drawings")
		(19 "Cmts.User" user "User.Comments")
		(21 "Eco1.User" user "User.Eco1")
		(23 "Eco2.User" user "User.Eco2")
		(25 "Edge.Cuts" user "Board Geometry/Outline")
		(27 "Margin" user)
		(31 "F.CrtYd" user "Package Geometry/Place Bound Top")
		(29 "B.CrtYd" user "Package Geometry/Place Bound Bottom")
		(35 "F.Fab" user "Ref Des/Assembly Top")
		(33 "B.Fab" user "Ref Des/Assembly Bottom")
	)
	(footprint ""
		(layer "F.Cu")
		(at 156.0957 -387.342634)
		(property "Reference" "U6016"
			(at -8.08609 -8.07466 0)
			(unlocked yes)
			(layer "F.SilkS")
			(effects
				(font
					(size 0.7874 0.5842)
					(thickness 0.1524)
				)
				(justify left)
			)
		)
		(property "Value" ""
			(at 0 0 0)
			(layer "F.Fab")
			(effects
				(font
					(size 1.27 1.27)
				)
			)
		)
		(duplicate_pad_numbers_are_jumpers no)
		(pad "BV32" smd circle
			(at 1.20269 2.724912)
			(size 0.381 0.381)
			(layers "F.Cu" "F.Mask" "F.Paste")
			(net "GND")
		)
		(pad "BW2" smd circle
			(at 1.150112 -3.41884)
			(size 0.3048 0.3048)
			(layers "F.Cu" "F.Mask" "F.Paste")
			(net "GND")
		)
		(pad "BW34" smd circle
			(at 1.150112 3.420364)
			(size 0.3048 0.3048)
			(layers "F.Cu" "F.Mask" "F.Paste")
			(net "GND")
		)
		(pad "BY1" smd oval
			(at 0.849884 -3.938524)
			(size 0.254 0.3302)
			(layers "F.Cu" "F.Mask" "F.Paste")
			(net "GND")
		)
		(pad "BY35" smd oval
			(at 0.849884 3.940048)
			(size 0.254 0.3302)
			(layers "F.Cu" "F.Mask" "F.Paste")
			(net "GND")
		)
		(pad "C2" smd circle
			(at 10.750042 -3.41884)
			(size 0.3048 0.3048)
			(layers "F.Cu" "F.Mask" "F.Paste")
			(net "NCF_CPU1_P2_GND")
		)
		(pad "C34" smd circle
			(at 10.750042 3.420364)
			(size 0.3048 0.3048)
			(layers "F.Cu" "F.Mask" "F.Paste")
			(net "NCF_CPU1_P2_GND")
		)
		(pad "CA7" smd circle
			(at 0.80264 -2.12471)
			(size 0.381 0.381)
			(layers "F.Cu" "F.Mask" "F.Paste")
			(net "P5E_CPU1_P2_TX_BUF_DP<8>")
		)
		(pad "CA26" smd circle
			(at 0.80264 1.339342)
			(size 0.381 0.381)
			(layers "F.Cu" "F.Mask" "F.Paste")
			(net "P5E_CPU1_P2_RX_DP<8>")
		)
		(pad "CB2" smd circle
			(at 0.54991 -3.41884)
			(size 0.3048 0.3048)
			(layers "F.Cu" "F.Mask" "F.Paste")
			(net "P5E_CPU1_P2_RX_BUF_DN<8>")
		)
		(pad "CB34" smd circle
			(at 0.54991 3.420364)
			(size 0.3048 0.3048)
			(layers "F.Cu" "F.Mask" "F.Paste")
			(net "P5E_CPU1_P2_TX_C_DN<8>")
		)
		(pad "CC10" smd circle
			(at 0.40259 -1.431798)
			(size 0.381 0.381)
			(layers "F.Cu" "F.Mask" "F.Paste")
			(net "P5E_CPU1_P2_TX_BUF_DN<8>")
		)
		(pad "CC29" smd circle
			(at 0.40259 2.032254)
			(size 0.381 0.381)
			(layers "F.Cu" "F.Mask" "F.Paste")
			(net "P5E_CPU1_P2_RX_DN<8>")
		)
		(pad "CD1" smd oval
			(at 0.249936 -3.938524)
			(size 0.254 0.3302)
			(layers "F.Cu" "F.Mask" "F.Paste")
			(net "P5E_CPU1_P2_RX_BUF_DP<8>")
		)
		(pad "CD35" smd oval
			(at 0.249936 3.940048)
			(size 0.254 0.3302)
			(layers "F.Cu" "F.Mask" "F.Paste")
			(net "P5E_CPU1_P2_TX_C_DP<8>")
		)
		(pad "CE4" smd circle
			(at 0.00254 -2.817368)
			(size 0.381 0.381)
			(layers "F.Cu" "F.Mask" "F.Paste")
			(net "GND")
		)
		(pad "CE13" smd circle
			(at 0.00254 -0.79629)
			(size 0.3048 0.3048)
			(layers "F.Cu" "F.Mask" "F.Paste")
			(net "GND")
		)
		(pad "CE17" smd circle
			(at 0.00254 -0.296164)
			(size 0.3048 0.3048)
			(layers "F.Cu" "F.Mask" "F.Paste")
			(net "P1V8_CPU1_RT2_1A")
		)
		(pad "CE20" smd circle
			(at 0.00254 0.203708)
			(size 0.3048 0.3048)
			(layers "F.Cu" "F.Mask" "F.Paste")
			(net "P1V8_CPU1_RT2_1A")
		)
		(pad "CE22" smd circle
			(at 0.00254 0.703834)
			(size 0.3048 0.3048)
			(layers "F.Cu" "F.Mask" "F.Paste")
			(net "GND")
		)
		(pad "CE32" smd circle
			(at 0.00254 2.724912)
			(size 0.381 0.381)
			(layers "F.Cu" "F.Mask" "F.Paste")
			(net "GND")
		)
		(pad "CF2" smd circle
			(at -0.050038 -3.41884)
			(size 0.3048 0.3048)
			(layers "F.Cu" "F.Mask" "F.Paste")
			(net "GND")
		)
		(pad "CF34" smd circle
			(at -0.050038 3.420364)
			(size 0.3048 0.3048)
			(layers "F.Cu" "F.Mask" "F.Paste")
			(net "GND")
		)
		(pad "CG1" smd oval
			(at -0.350012 -3.938524)
			(size 0.254 0.3302)
			(layers "F.Cu" "F.Mask" "F.Paste")
			(net "GND")
		)
		(pad "CG35" smd oval
			(at -0.350012 3.940048)
			(size 0.254 0.3302)
			(layers "F.Cu" "F.Mask" "F.Paste")
			(net "GND")
		)
		(pad "CH7" smd circle
			(at -0.39751 -2.12471)
			(size 0.381 0.381)
			(layers "F.Cu" "F.Mask" "F.Paste")
			(net "P5E_CPU1_P2_TX_BUF_DP<7>")
		)
		(pad "CH26" smd circle
			(at -0.39751 1.339342)
			(size 0.381 0.381)
			(layers "F.Cu" "F.Mask" "F.Paste")
			(net "P5E_CPU1_P2_RX_DP<7>")
		)
		(pad "CJ2" smd circle
			(at -0.649986 -3.41884)
			(size 0.3048 0.3048)
			(layers "F.Cu" "F.Mask" "F.Paste")
			(net "P5E_CPU1_P2_RX_BUF_DN<7>")
		)
		(pad "CJ34" smd circle
			(at -0.649986 3.420364)
			(size 0.3048 0.3048)
			(layers "F.Cu" "F.Mask" "F.Paste")
			(net "P5E_CPU1_P2_TX_C_DN<7>")
		)
		(pad "CK10" smd circle
			(at -0.797306 -1.431798)
			(size 0.381 0.381)
			(layers "F.Cu" "F.Mask" "F.Paste")
			(net "P5E_CPU1_P2_TX_BUF_DN<7>")
		)
		(pad "CK29" smd circle
			(at -0.797306 2.032254)
			(size 0.381 0.381)
			(layers "F.Cu" "F.Mask" "F.Paste")
			(net "P5E_CPU1_P2_RX_DN<7>")
		)
		(pad "CL1" smd oval
			(at -0.94996 -3.938524)
			(size 0.254 0.3302)
			(layers "F.Cu" "F.Mask" "F.Paste")
			(net "P5E_CPU1_P2_RX_BUF_DP<7>")
		)
		(pad "CL35" smd oval
			(at -0.94996 3.940048)
			(size 0.254 0.3302)
			(layers "F.Cu" "F.Mask" "F.Paste")
			(net "P5E_CPU1_P2_TX_C_DP<7>")
		)
		(pad "CM4" smd circle
			(at -1.197356 -2.817368)
			(size 0.381 0.381)
			(layers "F.Cu" "F.Mask" "F.Paste")
			(net "GND")
		)
		(pad "CM13" smd circle
			(at -1.197356 -0.79629)
			(size 0.3048 0.3048)
			(layers "F.Cu" "F.Mask" "F.Paste")
			(net "GND")
		)
		(pad "CM17" smd circle
			(at -1.197356 -0.296164)
			(size 0.3048 0.3048)
			(layers "F.Cu" "F.Mask" "F.Paste")
			(net "P1V8_CPU1_RT2_1A")
		)
		(pad "CM20" smd circle
			(at -1.197356 0.203708)
			(size 0.3048 0.3048)
			(layers "F.Cu" "F.Mask" "F.Paste")
			(net "P1V8_CPU1_RT2_1A")
		)
		(pad "CM22" smd circle
			(at -1.197356 0.703834)
			(size 0.3048 0.3048)
			(layers "F.Cu" "F.Mask" "F.Paste")
			(net "GND")
		)
		(pad "CM32" smd circle
			(at -1.197356 2.724912)
			(size 0.381 0.381)
			(layers "F.Cu" "F.Mask" "F.Paste")
			(net "GND")
		)
		(pad "CN2" smd circle
			(at -1.249934 -3.41884)
			(size 0.3048 0.3048)
			(layers "F.Cu" "F.Mask" "F.Paste")
			(net "GND")
		)
		(pad "CN34" smd circle
			(at -1.249934 3.420364)
			(size 0.3048 0.3048)
			(layers "F.Cu" "F.Mask" "F.Paste")
			(net "GND")
		)
		(pad "CP1" smd oval
			(at -1.549908 -3.938524)
			(size 0.254 0.3302)
			(layers "F.Cu" "F.Mask" "F.Paste")
			(net "GND")
		)
		(pad "CP35" smd oval
			(at -1.549908 3.940048)
			(size 0.254 0.3302)
			(layers "F.Cu" "F.Mask" "F.Paste")
			(net "GND")
		)
		(pad "CR7" smd circle
			(at -1.597406 -2.12471)
			(size 0.381 0.381)
			(layers "F.Cu" "F.Mask" "F.Paste")
			(net "P5E_CPU1_P2_TX_BUF_DP<6>")
		)
		(pad "CR26" smd circle
			(at -1.597406 1.339342)
			(size 0.381 0.381)
			(layers "F.Cu" "F.Mask" "F.Paste")
			(net "P5E_CPU1_P2_RX_DP<6>")
		)
		(pad "CT2" smd circle
			(at -1.849882 -3.41884)
			(size 0.3048 0.3048)
			(layers "F.Cu" "F.Mask" "F.Paste")
			(net "P5E_CPU1_P2_RX_BUF_DN<6>")
		)
		(pad "CT34" smd circle
			(at -1.849882 3.420364)
			(size 0.3048 0.3048)
			(layers "F.Cu" "F.Mask" "F.Paste")
			(net "P5E_CPU1_P2_TX_C_DN<6>")
		)
		(pad "CU10" smd circle
			(at -1.997456 -1.431798)
			(size 0.381 0.381)
			(layers "F.Cu" "F.Mask" "F.Paste")
			(net "P5E_CPU1_P2_TX_BUF_DN<6>")
		)
		(pad "CU29" smd circle
			(at -1.997456 2.032254)
			(size 0.381 0.381)
			(layers "F.Cu" "F.Mask" "F.Paste")
			(net "P5E_CPU1_P2_RX_DN<6>")
		)
		(pad "CV1" smd oval
			(at -2.15011 -3.938524)
			(size 0.254 0.3302)
			(layers "F.Cu" "F.Mask" "F.Paste")
			(net "P5E_CPU1_P2_RX_BUF_DP<6>")
		)
		(pad "CV35" smd oval
			(at -2.15011 3.940048)
			(size 0.254 0.3302)
			(layers "F.Cu" "F.Mask" "F.Paste")
			(net "P5E_CPU1_P2_TX_C_DP<6>")
		)
		(pad "CW4" smd circle
			(at -2.397506 -2.817368)
			(size 0.381 0.381)
			(layers "F.Cu" "F.Mask" "F.Paste")
			(net "GND")
		)
		(pad "CW13" smd circle
			(at -2.397506 -0.79629)
			(size 0.3048 0.3048)
			(layers "F.Cu" "F.Mask" "F.Paste")
			(net "GND")
		)
		(pad "CW17" smd circle
			(at -2.397506 -0.296164)
			(size 0.3048 0.3048)
			(layers "F.Cu" "F.Mask" "F.Paste")
			(net "P0V9_CPU1_RT_2D")
		)
		(pad "CW20" smd circle
			(at -2.397506 0.203708)
			(size 0.3048 0.3048)
			(layers "F.Cu" "F.Mask" "F.Paste")
			(net "P0V9_CPU1_RT_2D")
		)
		(pad "CW22" smd circle
			(at -2.397506 0.703834)
			(size 0.3048 0.3048)
			(layers "F.Cu" "F.Mask" "F.Paste")
			(net "GND")
		)
		(pad "CW32" smd circle
			(at -2.397506 2.724912)
			(size 0.381 0.381)
			(layers "F.Cu" "F.Mask" "F.Paste")
			(net "GND")
		)
		(pad "CY2" smd circle
			(at -2.450084 -3.41884)
			(size 0.3048 0.3048)
			(layers "F.Cu" "F.Mask" "F.Paste")
			(net "GND")
		)
		(pad "CY34" smd circle
			(at -2.450084 3.420364)
			(size 0.3048 0.3048)
			(layers "F.Cu" "F.Mask" "F.Paste")
			(net "GND")
		)
		(pad "D1" smd oval
			(at 10.450068 -3.938524)
			(size 0.254 0.3302)
			(layers "F.Cu" "F.Mask" "F.Paste")
			(net "NCF_CPU1_P2_GND")
		)
		(pad "D35" smd oval
			(at 10.450068 3.940048)
			(size 0.254 0.3302)
			(layers "F.Cu" "F.Mask" "F.Paste")
			(net "NCF_CPU1_P2_GND")
		)
		(pad "DA1" smd oval
			(at -2.750058 -3.938524)
			(size 0.254 0.3302)
			(layers "F.Cu" "F.Mask" "F.Paste")
			(net "GND")
		)
		(pad "DA35" smd oval
			(at -2.750058 3.940048)
			(size 0.254 0.3302)
			(layers "F.Cu" "F.Mask" "F.Paste")
			(net "GND")
		)
		(pad "DB7" smd circle
			(at -2.797302 -2.12471)
			(size 0.381 0.381)
			(layers "F.Cu" "F.Mask" "F.Paste")
			(net "P5E_CPU1_P2_TX_BUF_DP<5>")
		)
		(pad "DB26" smd circle
			(at -2.797302 1.339342)
			(size 0.381 0.381)
			(layers "F.Cu" "F.Mask" "F.Paste")
			(net "P5E_CPU1_P2_RX_DP<5>")
		)
		(pad "DC2" smd circle
			(at -3.050032 -3.41884)
			(size 0.3048 0.3048)
			(layers "F.Cu" "F.Mask" "F.Paste")
			(net "P5E_CPU1_P2_RX_BUF_DN<5>")
		)
		(pad "DC34" smd circle
			(at -3.050032 3.420364)
			(size 0.3048 0.3048)
			(layers "F.Cu" "F.Mask" "F.Paste")
			(net "P5E_CPU1_P2_TX_C_DN<5>")
		)
		(pad "DD10" smd circle
			(at -3.197352 -1.431798)
			(size 0.381 0.381)
			(layers "F.Cu" "F.Mask" "F.Paste")
			(net "P5E_CPU1_P2_TX_BUF_DN<5>")
		)
		(pad "DD29" smd circle
			(at -3.197352 2.032254)
			(size 0.381 0.381)
			(layers "F.Cu" "F.Mask" "F.Paste")
			(net "P5E_CPU1_P2_RX_DN<5>")
		)
		(pad "DE1" smd oval
			(at -3.350006 -3.938524)
			(size 0.254 0.3302)
			(layers "F.Cu" "F.Mask" "F.Paste")
			(net "P5E_CPU1_P2_RX_BUF_DP<5>")
		)
		(pad "DE35" smd oval
			(at -3.350006 3.940048)
			(size 0.254 0.3302)
			(layers "F.Cu" "F.Mask" "F.Paste")
			(net "P5E_CPU1_P2_TX_C_DP<5>")
		)
		(pad "DF4" smd circle
			(at -3.597402 -2.817368)
			(size 0.381 0.381)
			(layers "F.Cu" "F.Mask" "F.Paste")
			(net "GND")
		)
		(pad "DF13" smd circle
			(at -3.597402 -0.79629)
			(size 0.3048 0.3048)
			(layers "F.Cu" "F.Mask" "F.Paste")
			(net "GND")
		)
		(pad "DF17" smd circle
			(at -3.597402 -0.296164)
			(size 0.3048 0.3048)
			(layers "F.Cu" "F.Mask" "F.Paste")
			(net "P0V9_CPU1_RT2_2A_2D")
		)
		(pad "DF20" smd circle
			(at -3.597402 0.203708)
			(size 0.3048 0.3048)
			(layers "F.Cu" "F.Mask" "F.Paste")
			(net "P0V9_CPU1_RT2_2A_2D")
		)
		(pad "DF22" smd circle
			(at -3.597402 0.703834)
			(size 0.3048 0.3048)
			(layers "F.Cu" "F.Mask" "F.Paste")
			(net "GND")
		)
		(pad "DF32" smd circle
			(at -3.597402 2.724912)
			(size 0.381 0.381)
			(layers "F.Cu" "F.Mask" "F.Paste")
			(net "GND")
		)
		(pad "DG2" smd circle
			(at -3.64998 -3.41884)
			(size 0.3048 0.3048)
			(layers "F.Cu" "F.Mask" "F.Paste")
			(net "GND")
		)
		(pad "DG34" smd circle
			(at -3.64998 3.420364)
			(size 0.3048 0.3048)
			(layers "F.Cu" "F.Mask" "F.Paste")
			(net "GND")
		)
		(pad "DH1" smd oval
			(at -3.949954 -3.938524)
			(size 0.254 0.3302)
			(layers "F.Cu" "F.Mask" "F.Paste")
			(net "GND")
		)
		(pad "DH35" smd oval
			(at -3.949954 3.940048)
			(size 0.254 0.3302)
			(layers "F.Cu" "F.Mask" "F.Paste")
			(net "GND")
		)
		(pad "DJ7" smd circle
			(at -3.997452 -2.12471)
			(size 0.381 0.381)
			(layers "F.Cu" "F.Mask" "F.Paste")
			(net "P5E_CPU1_P2_TX_BUF_DP<4>")
		)
		(pad "DJ26" smd circle
			(at -3.997452 1.339342)
			(size 0.381 0.381)
			(layers "F.Cu" "F.Mask" "F.Paste")
			(net "P5E_CPU1_P2_RX_DP<4>")
		)
		(pad "DK2" smd circle
			(at -4.249928 -3.41884)
			(size 0.3048 0.3048)
			(layers "F.Cu" "F.Mask" "F.Paste")
			(net "P5E_CPU1_P2_RX_BUF_DN<4>")
		)
		(pad "DK34" smd circle
			(at -4.249928 3.420364)
			(size 0.3048 0.3048)
			(layers "F.Cu" "F.Mask" "F.Paste")
			(net "P5E_CPU1_P2_TX_C_DN<4>")
		)
		(pad "DL10" smd circle
			(at -4.397502 -1.431798)
			(size 0.381 0.381)
			(layers "F.Cu" "F.Mask" "F.Paste")
			(net "P5E_CPU1_P2_TX_BUF_DN<4>")
		)
		(pad "DL29" smd circle
			(at -4.397502 2.032254)
			(size 0.381 0.381)
			(layers "F.Cu" "F.Mask" "F.Paste")
			(net "P5E_CPU1_P2_RX_DN<4>")
		)
		(pad "DM1" smd oval
			(at -4.549902 -3.938524)
			(size 0.254 0.3302)
			(layers "F.Cu" "F.Mask" "F.Paste")
			(net "P5E_CPU1_P2_RX_BUF_DP<4>")
		)
		(pad "DM35" smd oval
			(at -4.549902 3.940048)
			(size 0.254 0.3302)
			(layers "F.Cu" "F.Mask" "F.Paste")
			(net "P5E_CPU1_P2_TX_C_DP<4>")
		)
		(pad "DN4" smd circle
			(at -4.797298 -2.817368)
			(size 0.381 0.381)
			(layers "F.Cu" "F.Mask" "F.Paste")
			(net "GND")
		)
		(pad "DN13" smd circle
			(at -4.797298 -0.79629)
			(size 0.3048 0.3048)
			(layers "F.Cu" "F.Mask" "F.Paste")
			(net "GND")
		)
		(pad "DN17" smd circle
			(at -4.797298 -0.296164)
			(size 0.3048 0.3048)
			(layers "F.Cu" "F.Mask" "F.Paste")
			(net "P0V9_CPU1_RT2_2A")
		)
		(pad "DN20" smd circle
			(at -4.797298 0.203708)
			(size 0.3048 0.3048)
			(layers "F.Cu" "F.Mask" "F.Paste")
			(net "P0V9_CPU1_RT2_2A")
		)
		(pad "DN22" smd circle
			(at -4.797298 0.703834)
			(size 0.3048 0.3048)
			(layers "F.Cu" "F.Mask" "F.Paste")
			(net "GND")
		)
		(pad "DN32" smd circle
			(at -4.797298 2.724912)
			(size 0.381 0.381)
			(layers "F.Cu" "F.Mask" "F.Paste")
			(net "GND")
		)
		(pad "DP2" smd circle
			(at -4.849876 -3.41884)
			(size 0.3048 0.3048)
			(layers "F.Cu" "F.Mask" "F.Paste")
			(net "GND")
		)
		(pad "DP34" smd circle
			(at -4.849876 3.420364)
			(size 0.3048 0.3048)
			(layers "F.Cu" "F.Mask" "F.Paste")
			(net "GND")
		)
		(pad "DR1" smd oval
			(at -5.150104 -3.938524)
			(size 0.254 0.3302)
			(layers "F.Cu" "F.Mask" "F.Paste")
			(net "GND")
		)
		(pad "DR35" smd oval
			(at -5.150104 3.940048)
			(size 0.254 0.3302)
			(layers "F.Cu" "F.Mask" "F.Paste")
			(net "GND")
		)
		(pad "DT7" smd circle
			(at -5.197348 -2.12471)
			(size 0.381 0.381)
			(layers "F.Cu" "F.Mask" "F.Paste")
			(net "P5E_CPU1_P2_TX_BUF_DP<3>")
		)
		(pad "DT26" smd circle
			(at -5.197348 1.339342)
			(size 0.381 0.381)
			(layers "F.Cu" "F.Mask" "F.Paste")
			(net "P5E_CPU1_P2_RX_DP<3>")
		)
		(pad "DU2" smd circle
			(at -5.450078 -3.41884)
			(size 0.3048 0.3048)
			(layers "F.Cu" "F.Mask" "F.Paste")
			(net "P5E_CPU1_P2_RX_BUF_DN<3>")
		)
		(pad "DU34" smd circle
			(at -5.450078 3.420364)
			(size 0.3048 0.3048)
			(layers "F.Cu" "F.Mask" "F.Paste")
			(net "P5E_CPU1_P2_TX_C_DN<3>")
		)
		(pad "DV10" smd circle
			(at -5.597398 -1.431798)
			(size 0.381 0.381)
			(layers "F.Cu" "F.Mask" "F.Paste")
			(net "P5E_CPU1_P2_TX_BUF_DN<3>")
		)
		(pad "DV29" smd circle
			(at -5.597398 2.032254)
			(size 0.381 0.381)
			(layers "F.Cu" "F.Mask" "F.Paste")
			(net "P5E_CPU1_P2_RX_DN<3>")
		)
		(pad "DW1" smd oval
			(at -5.750052 -3.938524)
			(size 0.254 0.3302)
			(layers "F.Cu" "F.Mask" "F.Paste")
			(net "P5E_CPU1_P2_RX_BUF_DP<3>")
		)
		(pad "DW35" smd oval
			(at -5.750052 3.940048)
			(size 0.254 0.3302)
			(layers "F.Cu" "F.Mask" "F.Paste")
			(net "P5E_CPU1_P2_TX_C_DP<3>")
		)
		(pad "DY4" smd circle
			(at -5.997448 -2.817368)
			(size 0.381 0.381)
			(layers "F.Cu" "F.Mask" "F.Paste")
			(net "GND")
		)
		(pad "DY13" smd circle
			(at -5.997448 -0.79629)
			(size 0.3048 0.3048)
			(layers "F.Cu" "F.Mask" "F.Paste")
			(net "GND")
		)
		(pad "DY17" smd circle
			(at -5.997448 -0.296164)
			(size 0.3048 0.3048)
			(layers "F.Cu" "F.Mask" "F.Paste")
			(net "P0V9_CPU1_RT2_2A")
		)
		(pad "DY20" smd circle
			(at -5.997448 0.203708)
			(size 0.3048 0.3048)
			(layers "F.Cu" "F.Mask" "F.Paste")
			(net "P0V9_CPU1_RT2_2A")
		)
		(pad "DY22" smd circle
			(at -5.997448 0.703834)
			(size 0.3048 0.3048)
			(layers "F.Cu" "F.Mask" "F.Paste")
			(net "GND")
		)
	)
)
